# S9S_MB_2U (Grand Teton) — schematic netlist excerpt (pin names and nets, part order shuffled) for the footprints in the layout excerpt that follows; sources: Cadence DE-HDL packaged netlist, KiCad conversion of 03242023_DA0F0TMBIJ0_F0T_Motherboard_J_brd_V01_OCP.brd

R365  Q_RES  0 5% CHIP  pkg 0402LF  page 218 : A = FM_CPU_RMCA_CATERR_LVT3_R_N ; B = CPU_RMCA_CATERR_LVT3_N
C1301  Q_CAP  1000PF 50V 5% X7R  pkg 0402  page 281 : A = PWRGD_PVPP_HBM_CPU0_R ; B = GND

(kicad_pcb
	(version 20260206)
	(generator "pcbnew")
	(generator_version "10.0")
	(general
		(thickness 1.6)
		(legacy_teardrops no)
	)
	(paper "A4")
	(title_block
		(title "03242023_DA0F0TMBIJ0_F0T_Motherboard_J_brd_V01_OCP.brd")
		(comment 1 "Grand Teton / footprints 215-216 of 6105")
	)
	(layers
		(0 "F.Cu" signal "TOP")
		(4 "In1.Cu" signal "GND")
		(6 "In2.Cu" signal "IN1")
		(8 "In3.Cu" signal "GND1")
		(10 "In4.Cu" signal "IN2")
		(12 "In5.Cu" signal "GND2")
		(14 "In6.Cu" signal "IN3")
		(16 "In7.Cu" signal "GND3")
		(18 "In8.Cu" signal "VCC")
		(20 "In9.Cu" signal "VCC1")
		(22 "In10.Cu" signal "GND4")
		(24 "In11.Cu" signal "IN4")
		(26 "In12.Cu" signal "GND5")
		(28 "In13.Cu" signal "IN5")
		(30 "In14.Cu" signal "GND6")
		(32 "In15.Cu" signal "IN6")
		(34 "In16.Cu" signal "GND7")
		(2 "B.Cu" signal "BOTTOM")
		(9 "F.Adhes" user "F.Adhesive")
		(11 "B.Adhes" user "B.Adhesive")
		(13 "F.Paste" user "Package Geometry/Pastemask Top")
		(15 "B.Paste" user "Package Geometry/Pastemask Bottom")
		(5 "F.SilkS" user "Ref Des/Silkscreen Top")
		(7 "B.SilkS" user "Ref Des/Silkscreen Bottom")
		(1 "F.Mask" user "Board Geometry/Soldermask Top")
		(3 "B.Mask" user "Board Geometry/Soldermask Bottom")
		(17 "Dwgs.User" user "User.Drawings")
		(19 "Cmts.User" user "User.Comments")
		(21 "Eco1.User" user "User.Eco1")
		(23 "Eco2.User" user "User.Eco2")
		(25 "Edge.Cuts" user "Board Geometry/Outline")
		(27 "Margin" user)
		(31 "F.CrtYd" user "Package Geometry/Place Bound Top")
		(29 "B.CrtYd" user "Package Geometry/Place Bound Bottom")
		(35 "F.Fab" user "Ref Des/Assembly Top")
		(33 "B.Fab" user "Ref Des/Assembly Bottom")
	)
	(footprint ""
		(layer "F.Cu")
		(at 201.73188 -108.422948 -90)
		(property "Reference" "R365"
			(at 0 0 270)
			(layer "F.SilkS")
			(hide yes)
			(effects
				(font
					(size 1.27 1.27)
				)
			)
		)
		(property "Value" ""
			(at 0 0 270)
			(layer "F.Fab")
			(effects
				(font
					(size 1.27 1.27)
				)
			)
		)
		(duplicate_pad_numbers_are_jumpers no)
		(fp_line
			(start -0.7874 0.4064)
			(end -0.7874 -0.4064)
			(stroke
				(width 0.1524)
				(type default)
			)
			(layer "F.SilkS")
		)
		(fp_line
			(start 0.7874 0.4064)
			(end -0.7874 0.4064)
			(stroke
				(width 0.1524)
				(type default)
			)
			(layer "F.SilkS")
		)
		(fp_line
			(start -0.7874 -0.4064)
			(end 0.7874 -0.4064)
			(stroke
				(width 0.1524)
				(type default)
			)
			(layer "F.SilkS")
		)
		(fp_line
			(start 0.7874 -0.4064)
			(end 0.7874 0.4064)
			(stroke
				(width 0.1524)
				(type default)
			)
			(layer "F.SilkS")
		)
		(fp_line
			(start -0.67945 0.3048)
			(end -0.67945 -0.305054)
			(stroke
				(width 0.1)
				(type default)
			)
			(layer "F.Fab")
		)
		(fp_line
			(start -0.12065 0.3048)
			(end -0.67945 0.3048)
			(stroke
				(width 0.1)
				(type default)
			)
			(layer "F.Fab")
		)
		(fp_line
			(start 0.120396 0.3048)
			(end 0.120396 0.2794)
			(stroke
				(width 0.1)
				(type default)
			)
			(layer "F.Fab")
		)
		(fp_line
			(start 0.67945 0.3048)
			(end 0.120396 0.3048)
			(stroke
				(width 0.1)
				(type default)
			)
			(layer "F.Fab")
		)
		(fp_line
			(start -0.12065 0.2794)
			(end -0.12065 0.3048)
			(stroke
				(width 0.1)
				(type default)
			)
			(layer "F.Fab")
		)
		(fp_line
			(start 0.120396 0.2794)
			(end -0.12065 0.2794)
			(stroke
				(width 0.1)
				(type default)
			)
			(layer "F.Fab")
		)
		(fp_line
			(start -0.12065 -0.2794)
			(end 0.12065 -0.2794)
			(stroke
				(width 0.1)
				(type default)
			)
			(layer "F.Fab")
		)
		(fp_line
			(start 0.12065 -0.2794)
			(end 0.12065 -0.3048)
			(stroke
				(width 0.1)
				(type default)
			)
			(layer "F.Fab")
		)
		(fp_line
			(start 0.12065 -0.3048)
			(end 0.67945 -0.3048)
			(stroke
				(width 0.1)
				(type default)
			)
			(layer "F.Fab")
		)
		(fp_line
			(start 0.67945 -0.3048)
			(end 0.67945 0.3048)
			(stroke
				(width 0.1)
				(type default)
			)
			(layer "F.Fab")
		)
		(fp_line
			(start -0.67945 -0.305054)
			(end -0.12065 -0.305054)
			(stroke
				(width 0.1)
				(type default)
			)
			(layer "F.Fab")
		)
		(fp_line
			(start -0.12065 -0.305054)
			(end -0.12065 -0.2794)
			(stroke
				(width 0.1)
				(type default)
			)
			(layer "F.Fab")
		)
		(pad "1" smd circle
			(at -0.40005 0 270)
			(size 0 0)
			(layers "F.Cu" "F.Mask" "F.Paste")
			(net "FM_CPU_RMCA_CATERR_LVT3_R_N")
		)
		(pad "2" smd circle
			(at 0.40005 0 270)
			(size 0 0)
			(layers "F.Cu" "F.Mask" "F.Paste")
			(net "CPU_RMCA_CATERR_LVT3_N")
		)
	)
	(footprint ""
		(layer "F.Cu")
		(at 366.629188 -355.651816 180)
		(property "Reference" "C1301"
			(at 0 0 180)
			(layer "F.SilkS")
			(hide yes)
			(effects
				(font
					(size 1.27 1.27)
				)
			)
		)
		(property "Value" ""
			(at 0 0 180)
			(layer "F.Fab")
			(effects
				(font
					(size 1.27 1.27)
				)
			)
		)
		(duplicate_pad_numbers_are_jumpers no)
		(fp_line
			(start 0.7874 0.4064)
			(end -0.7874 0.4064)
			(stroke
				(width 0.1524)
				(type default)
			)
			(layer "F.SilkS")
		)
		(fp_line
			(start 0.7874 -0.4064)
			(end 0.7874 0.4064)
			(stroke
				(width 0.1524)
				(type default)
			)
			(layer "F.SilkS")
		)
		(fp_line
			(start -0.7874 0.4064)
			(end -0.7874 -0.4064)
			(stroke
				(width 0.1524)
				(type default)
			)
			(layer "F.SilkS")
		)
		(fp_line
			(start -0.7874 -0.4064)
			(end 0.7874 -0.4064)
			(stroke
				(width 0.1524)
				(type default)
			)
			(layer "F.SilkS")
		)
		(fp_line
			(start 0.67945 0.3048)
			(end 0.120396 0.3048)
			(stroke
				(width 0.1)
				(type default)
			)
			(layer "F.Fab")
		)
		(fp_line
			(start 0.67945 -0.3048)
			(end 0.67945 0.3048)
			(stroke
				(width 0.1)
				(type default)
			)
			(layer "F.Fab")
		)
		(fp_line
			(start 0.12065 -0.2794)
			(end 0.12065 -0.3048)
			(stroke
				(width 0.1)
				(type default)
			)
			(layer "F.Fab")
		)
		(fp_line
			(start 0.12065 -0.3048)
			(end 0.67945 -0.3048)
			(stroke
				(width 0.1)
				(type default)
			)
			(layer "F.Fab")
		)
		(fp_line
			(start 0.120396 0.3048)
			(end 0.120396 0.2794)
			(stroke
				(width 0.1)
				(type default)
			)
			(layer "F.Fab")
		)
		(fp_line
			(start 0.120396 0.2794)
			(end -0.12065 0.2794)
			(stroke
				(width 0.1)
				(type default)
			)
			(layer "F.Fab")
		)
		(fp_line
			(start -0.12065 0.3048)
			(end -0.67945 0.3048)
			(stroke
				(width 0.1)
				(type default)
			)
			(layer "F.Fab")
		)
		(fp_line
			(start -0.12065 0.2794)
			(end -0.12065 0.3048)
			(stroke
				(width 0.1)
				(type default)
			)
			(layer "F.Fab")
		)
		(fp_line
			(start -0.12065 -0.2794)
			(end 0.12065 -0.2794)
			(stroke
				(width 0.1)
				(type default)
			)
			(layer "F.Fab")
		)
		(fp_line
			(start -0.12065 -0.305054)
			(end -0.12065 -0.2794)
			(stroke
				(width 0.1)
				(type default)
			)
			(layer "F.Fab")
		)
		(fp_line
			(start -0.67945 0.3048)
			(end -0.67945 -0.305054)
			(stroke
				(width 0.1)
				(type default)
			)
			(layer "F.Fab")
		)
		(fp_line
			(start -0.67945 -0.305054)
			(end -0.12065 -0.305054)
			(stroke
				(width 0.1)
				(type default)
			)
			(layer "F.Fab")
		)
		(pad "1" smd circle
			(at -0.40005 0 180)
			(size 0 0)
			(layers "F.Cu" "F.Mask" "F.Paste")
			(net "PWRGD_PVPP_HBM_CPU0_R")
		)
		(pad "2" smd circle
			(at 0.40005 0 180)
			(size 0 0)
			(layers "F.Cu" "F.Mask" "F.Paste")
			(net "GND")
		)
	)
)
